(kicad_pcb
	(version 20260206)
	(generator "pcbnew")
	(generator_version "10.0")
	(general
		(thickness 1.6)
		(legacy_teardrops no)
	)
	(paper "A4")
	(title_block
		(title "15969-1a.1015WZS0858.brd")
		(comment 1 "Tioga Pass / footprints 252-256 of 295")
	)
	(layers
		(0 "F.Cu" signal "TOP")
		(4 "In1.Cu" signal "L2GND")
		(6 "In2.Cu" signal "L3")
		(8 "In3.Cu" signal "L4")
		(10 "In4.Cu" signal "L5GND")
		(2 "B.Cu" signal "BOTTOM")
		(9 "F.Adhes" user "F.Adhesive")
		(11 "B.Adhes" user "B.Adhesive")
		(13 "F.Paste" user "Package Geometry/Pastemask Top")
		(15 "B.Paste" user "Package Geometry/Pastemask Bottom")
		(5 "F.SilkS" user "Ref Des/Silkscreen Top")
		(7 "B.SilkS" user "Ref Des/Silkscreen Bottom")
		(1 "F.Mask" user "Board Geometry/Soldermask Top")
		(3 "B.Mask" user "Board Geometry/Soldermask Bottom")
		(17 "Dwgs.User" user "User.Drawings")
		(19 "Cmts.User" user "User.Comments")
		(21 "Eco1.User" user "User.Eco1")
		(23 "Eco2.User" user "User.Eco2")
		(25 "Edge.Cuts" user "Board Geometry/Outline")
		(27 "Margin" user)
		(31 "F.CrtYd" user "Package Geometry/Place Bound Top")
		(29 "B.CrtYd" user "Package Geometry/Place Bound Bottom")
		(35 "F.Fab" user "Ref Des/Assembly Top")
		(33 "B.Fab" user "Ref Des/Assembly Bottom")
	)
	(footprint ""
		(layer "B.Cu")
		(at 22.2504 -23.9014 -90)
		(property "Reference" "U18"
			(at 0 0 90)
			(layer "B.SilkS")
			(hide yes)
			(effects
				(font
					(size 1.27 1.27)
				)
				(justify mirror)
			)
		)
		(property "Value" "INA230AIRGTR-GP"
			(at 5.6388 -6.1468 270)
			(unlocked yes)
			(layer "B.Fab")
			(hide yes)
			(effects
				(font
					(size 1.016 1.016)
					(thickness 0.1524)
				)
				(justify mirror)
			)
		)
		(property "Device Type" "QFN16-G1D8-UH40"
			(at 5.6388 -7.6708 270)
			(unlocked yes)
			(layer "B.Fab")
			(hide yes)
			(effects
				(font
					(size 1.016 1.016)
					(thickness 0.1524)
				)
				(justify mirror)
			)
		)
		(duplicate_pad_numbers_are_jumpers no)
		(fp_line
			(start -2.5146 2.5146)
			(end -2.5146 1.2446)
			(stroke
				(width 0.1524)
				(type default)
			)
			(layer "B.SilkS")
		)
		(fp_line
			(start -1.2446 2.5146)
			(end -2.5146 2.5146)
			(stroke
				(width 0.1524)
				(type default)
			)
			(layer "B.SilkS")
		)
		(fp_line
			(start 2.5146 2.5146)
			(end 1.2446 2.5146)
			(stroke
				(width 0.1524)
				(type default)
			)
			(layer "B.SilkS")
		)
		(fp_line
			(start 0.248666 2.287524)
			(end 0.248666 3.049524)
			(stroke
				(width 0.1524)
				(type default)
			)
			(layer "B.SilkS")
		)
		(fp_line
			(start 2.5146 1.2446)
			(end 2.5146 2.5146)
			(stroke
				(width 0.1524)
				(type default)
			)
			(layer "B.SilkS")
		)
		(fp_line
			(start -2.287524 -0.260604)
			(end -2.795524 -0.260604)
			(stroke
				(width 0.1524)
				(type default)
			)
			(layer "B.SilkS")
		)
		(fp_line
			(start 2.287524 -0.753364)
			(end 2.795524 -0.753364)
			(stroke
				(width 0.1524)
				(type default)
			)
			(layer "B.SilkS")
		)
		(fp_line
			(start 1.2446 -2.5146)
			(end 2.5146 -2.5146)
			(stroke
				(width 0.1524)
				(type default)
			)
			(layer "B.SilkS")
		)
		(fp_line
			(start 2.5146 -2.5146)
			(end 2.5146 -1.2446)
			(stroke
				(width 0.1524)
				(type default)
			)
			(layer "B.SilkS")
		)
		(fp_poly
			(pts
				(xy -1.2446 -2.5146) (xy -2.5146 -2.5146) (xy -2.5146 -1.2446)
			)
			(stroke
				(width 0)
				(type default)
			)
			(fill yes)
			(layer "B.SilkS")
		)
		(fp_rect
			(start 1.4986 1.4986)
			(end -1.4986 -1.4986)
			(stroke
				(width 0)
				(type default)
			)
			(fill no)
			(layer "B.CrtYd")
		)
		(fp_poly
			(pts
				(xy 1.4986 -1.4986) (xy 2.5146 -1.4986) (xy 2.5146 -2.5146) (xy -2.5146 -2.5146) (xy -2.5146 2.5146)
				(xy 2.5146 2.5146) (xy 2.5146 -1.4859) (xy 1.4986 -1.4859) (xy 1.4986 1.4986) (xy -1.4986 1.4986)
				(xy -1.4986 -1.4986)
			)
			(stroke
				(width 0)
				(type default)
			)
			(fill no)
			(layer "B.CrtYd")
		)
		(fp_rect
			(start 2.5146 2.5146)
			(end -2.5146 -2.5146)
			(stroke
				(width 0)
				(type default)
			)
			(fill no)
			(layer "B.Fab")
		)
		(pad "1" smd rect
			(at -0.750062 -1.550924 90)
			(size 0.3048 0.9144)
			(layers "B.Cu" "B.Mask" "B.Paste")
			(net "ATX_VMONITOR_A1")
		)
		(pad "2" smd rect
			(at -0.249936 -1.550924 90)
			(size 0.3048 0.9144)
			(layers "B.Cu" "B.Mask" "B.Paste")
			(net "ATX_VMONITOR_A0")
		)
		(pad "3" smd rect
			(at 0.249936 -1.550924 90)
			(size 0.3048 0.9144)
			(layers "B.Cu" "B.Mask" "B.Paste")
			(net "SMB_VMONITOR_ATX_ALERT_N")
		)
		(pad "4" smd rect
			(at 0.750062 -1.550924 90)
			(size 0.3048 0.9144)
			(layers "B.Cu" "B.Mask" "B.Paste")
			(net "SMB_VMONITOR_ATX_MUX_SDA")
		)
		(pad "5" smd rect
			(at 1.550924 -0.750062 90)
			(size 0.9144 0.3048)
			(layers "B.Cu" "B.Mask" "B.Paste")
			(net "SMB_VMONITOR_ATX_MUX_SCL")
		)
		(pad "6" smd rect
			(at 1.550924 -0.249936 90)
			(size 0.9144 0.3048)
			(layers "B.Cu" "B.Mask" "B.Paste")
			(net "Net_214")
		)
		(pad "7" smd rect
			(at 1.550924 0.249936 90)
			(size 0.9144 0.3048)
			(layers "B.Cu" "B.Mask" "B.Paste")
			(net "Net_215")
		)
		(pad "8" smd rect
			(at 1.550924 0.750062 90)
			(size 0.9144 0.3048)
			(layers "B.Cu" "B.Mask" "B.Paste")
			(net "Net_216")
		)
		(pad "9" smd rect
			(at 0.750062 1.550924 90)
			(size 0.3048 0.9144)
			(layers "B.Cu" "B.Mask" "B.Paste")
			(net "P3V3_STBY")
		)
		(pad "10" smd rect
			(at 0.249936 1.550924 90)
			(size 0.3048 0.9144)
			(layers "B.Cu" "B.Mask" "B.Paste")
			(net "GND")
		)
		(pad "11" smd rect
			(at -0.249936 1.550924 90)
			(size 0.3048 0.9144)
			(layers "B.Cu" "B.Mask" "B.Paste")
			(net "P12V")
		)
		(pad "12" smd rect
			(at -0.750062 1.550924 90)
			(size 0.3048 0.9144)
			(layers "B.Cu" "B.Mask" "B.Paste")
			(net "ATX_P12V_SENSE_VN_R")
		)
		(pad "13" smd rect
			(at -1.550924 0.750062 90)
			(size 0.9144 0.3048)
			(layers "B.Cu" "B.Mask" "B.Paste")
			(net "ATX_P12V_SENSE_VP_R")
		)
		(pad "14" smd rect
			(at -1.550924 0.249936 90)
			(size 0.9144 0.3048)
			(layers "B.Cu" "B.Mask" "B.Paste")
			(net "Net_211")
		)
		(pad "15" smd rect
			(at -1.550924 -0.249936 90)
			(size 0.9144 0.3048)
			(layers "B.Cu" "B.Mask" "B.Paste")
			(net "Net_212")
		)
		(pad "16" smd rect
			(at -1.550924 -0.750062 90)
			(size 0.9144 0.3048)
			(layers "B.Cu" "B.Mask" "B.Paste")
			(net "Net_213")
		)
		(pad "17" smd rect
			(at 0 0 90)
			(size 1.778 1.778)
			(layers "B.Cu" "B.Mask" "B.Paste")
			(net "GND")
		)
	)
	(footprint ""
		(layer "B.Cu")
		(at 127.44704 -5.9944 180)
		(property "Reference" "U2"
			(at 0 0 0)
			(layer "B.SilkS")
			(hide yes)
			(effects
				(font
					(size 1.27 1.27)
				)
				(justify mirror)
			)
		)
		(property "Value" "PCA9544APW-GP"
			(at 0 -11.8872 180)
			(unlocked yes)
			(layer "B.Fab")
			(hide yes)
			(effects
				(font
					(size 1.016 1.016)
					(thickness 0.1524)
				)
				(justify mirror)
			)
		)
		(property "Device Type" "TSOIC20H44"
			(at 0 -13.7922 180)
			(unlocked yes)
			(layer "B.Fab")
			(hide yes)
			(effects
				(font
					(size 1.016 1.016)
					(thickness 0.1524)
				)
				(justify mirror)
			)
		)
		(duplicate_pad_numbers_are_jumpers no)
		(fp_line
			(start 3.556 3.6322)
			(end 3.556 1.397)
			(stroke
				(width 0.508)
				(type default)
			)
			(layer "B.SilkS")
		)
		(fp_line
			(start 3.556 1.397)
			(end 3.556 1.778)
			(stroke
				(width 0.2032)
				(type default)
			)
			(layer "B.SilkS")
		)
		(fp_line
			(start 3.556 -1.397)
			(end 3.556 3.7084)
			(stroke
				(width 0.2032)
				(type default)
			)
			(layer "B.SilkS")
		)
		(fp_line
			(start 3.556 -1.397)
			(end -3.175 -1.397)
			(stroke
				(width 0.2032)
				(type default)
			)
			(layer "B.SilkS")
		)
		(fp_line
			(start 2.667 0)
			(end 3.556 0.889)
			(stroke
				(width 0.2032)
				(type default)
			)
			(layer "B.SilkS")
		)
		(fp_line
			(start 2.667 0)
			(end 3.556 -0.889)
			(stroke
				(width 0.2032)
				(type default)
			)
			(layer "B.SilkS")
		)
		(fp_line
			(start -3.175 1.397)
			(end 3.556 1.397)
			(stroke
				(width 0.2032)
				(type default)
			)
			(layer "B.SilkS")
		)
		(fp_line
			(start -3.175 -1.397)
			(end -3.175 1.397)
			(stroke
				(width 0.2032)
				(type default)
			)
			(layer "B.SilkS")
		)
		(fp_poly
			(pts
				(xy 3.25628 -1.8542) (xy -3.25628 -1.8542) (xy -3.25628 1.8542) (xy 3.25628 1.8542)
			)
			(stroke
				(width 0)
				(type default)
			)
			(fill yes)
			(layer "B.SilkS")
		)
		(fp_rect
			(start 3.556 3.81)
			(end -3.556 -3.81)
			(stroke
				(width 0)
				(type default)
			)
			(fill no)
			(layer "B.CrtYd")
		)
		(fp_poly
			(pts
				(xy 3.556 -3.81) (xy -3.556 -3.81) (xy -3.556 3.81) (xy 3.556 3.81)
			)
			(stroke
				(width 0)
				(type default)
			)
			(fill no)
			(layer "B.Fab")
		)
		(pad "1" smd rect
			(at 2.92608 2.8194)
			(size 0.3556 1.524)
			(layers "B.Cu" "B.Mask" "B.Paste")
			(net "SMB_P_HUB_A0")
		)
		(pad "2" smd rect
			(at 2.27584 2.8194)
			(size 0.3556 1.524)
			(layers "B.Cu" "B.Mask" "B.Paste")
			(net "SMB_P_HUB_A1")
		)
		(pad "3" smd rect
			(at 1.6256 2.8194)
			(size 0.3556 1.524)
			(layers "B.Cu" "B.Mask" "B.Paste")
			(net "SMB_P_HUB_A2")
		)
		(pad "4" smd rect
			(at 0.97536 2.8194)
			(size 0.3556 1.524)
			(layers "B.Cu" "B.Mask" "B.Paste")
			(net "SMB_PCIE_SLOT2_ALERT_N")
		)
		(pad "5" smd rect
			(at 0.32512 2.8194)
			(size 0.3556 1.524)
			(layers "B.Cu" "B.Mask" "B.Paste")
			(net "SMDAT_PCH_SLOT2")
		)
		(pad "6" smd rect
			(at -0.32512 2.8194)
			(size 0.3556 1.524)
			(layers "B.Cu" "B.Mask" "B.Paste")
			(net "SMCLK_PCH_SLOT2")
		)
		(pad "7" smd rect
			(at -0.97536 2.8194)
			(size 0.3556 1.524)
			(layers "B.Cu" "B.Mask" "B.Paste")
			(net "SMB_PCIE_SLOT3_ALERT_N")
		)
		(pad "8" smd rect
			(at -1.6256 2.8194)
			(size 0.3556 1.524)
			(layers "B.Cu" "B.Mask" "B.Paste")
			(net "SMDAT_PCH_SLOT3")
		)
		(pad "9" smd rect
			(at -2.27584 2.8194)
			(size 0.3556 1.524)
			(layers "B.Cu" "B.Mask" "B.Paste")
			(net "SMCLK_PCH_SLOT3")
		)
		(pad "10" smd rect
			(at -2.92608 2.8194)
			(size 0.3556 1.524)
			(layers "B.Cu" "B.Mask" "B.Paste")
			(net "GND")
		)
		(pad "11" smd rect
			(at -2.92608 -2.8194)
			(size 0.3556 1.524)
			(layers "B.Cu" "B.Mask" "B.Paste")
			(net "PU_P_I2CMUX_INT2_N")
		)
		(pad "12" smd rect
			(at -2.27584 -2.8194)
			(size 0.3556 1.524)
			(layers "B.Cu" "B.Mask" "B.Paste")
			(net "PU_P_MUX_SDA2")
		)
		(pad "13" smd rect
			(at -1.6256 -2.8194)
			(size 0.3556 1.524)
			(layers "B.Cu" "B.Mask" "B.Paste")
			(net "PU_P_MUX_SCL2")
		)
		(pad "14" smd rect
			(at -0.97536 -2.8194)
			(size 0.3556 1.524)
			(layers "B.Cu" "B.Mask" "B.Paste")
			(net "SMB_PCH_DEVICE_ALERT_N")
		)
		(pad "15" smd rect
			(at -0.32512 -2.8194)
			(size 0.3556 1.524)
			(layers "B.Cu" "B.Mask" "B.Paste")
			(net "SMDAT_PCH_DEVICE")
		)
		(pad "16" smd rect
			(at 0.32512 -2.8194)
			(size 0.3556 1.524)
			(layers "B.Cu" "B.Mask" "B.Paste")
			(net "SMCLK_PCH_DEVICE")
		)
		(pad "17" smd rect
			(at 0.97536 -2.8194)
			(size 0.3556 1.524)
			(layers "B.Cu" "B.Mask" "B.Paste")
			(net "SMB_PCH_ALERT_N")
		)
		(pad "18" smd rect
			(at 1.6256 -2.8194)
			(size 0.3556 1.524)
			(layers "B.Cu" "B.Mask" "B.Paste")
			(net "SMCLK_PCH_R")
		)
		(pad "19" smd rect
			(at 2.27584 -2.8194)
			(size 0.3556 1.524)
			(layers "B.Cu" "B.Mask" "B.Paste")
			(net "SMDAT_PCH_R")
		)
		(pad "20" smd rect
			(at 2.92608 -2.8194)
			(size 0.3556 1.524)
			(layers "B.Cu" "B.Mask" "B.Paste")
			(net "P3V3_STBY")
		)
	)
	(footprint ""
		(layer "B.Cu")
		(at 119.6594 -22.7838 180)
		(property "Reference" "R112"
			(at 0 0 0)
			(layer "B.SilkS")
			(hide yes)
			(effects
				(font
					(size 1.27 1.27)
				)
				(justify mirror)
			)
		)
		(property "Value" "0R2F-1-GP"
			(at -0.064008 -3.993896 180)
			(unlocked yes)
			(layer "B.Fab")
			(hide yes)
			(effects
				(font
					(size 1.016 1.016)
					(thickness 0.1524)
				)
				(justify mirror)
			)
		)
		(property "Device Type" "R402H16"
			(at -0.064008 -5.517896 180)
			(unlocked yes)
			(layer "B.Fab")
			(hide yes)
			(effects
				(font
					(size 1.016 1.016)
					(thickness 0.1524)
				)
				(justify mirror)
			)
		)
		(duplicate_pad_numbers_are_jumpers no)
		(fp_line
			(start 0.508 -0.9398)
			(end 0.508 0.9398)
			(stroke
				(width 0.1524)
				(type default)
			)
			(layer "B.SilkS")
		)
		(fp_line
			(start -0.508 -0.9398)
			(end 0.508 -0.9398)
			(stroke
				(width 0.1524)
				(type default)
			)
			(layer "B.SilkS")
		)
		(fp_rect
			(start 0.508 0.9398)
			(end -0.508 -0.9398)
			(stroke
				(width 0)
				(type default)
			)
			(fill no)
			(layer "B.CrtYd")
		)
		(fp_rect
			(start 0.508 0.9398)
			(end -0.508 -0.9398)
			(stroke
				(width 0)
				(type default)
			)
			(fill no)
			(layer "B.Fab")
		)
		(pad "1" smd custom
			(at 0 -0.4445)
			(size 0.1397 0.1397)
			(layers "B.Cu" "B.Mask" "B.Paste")
			(net "SMDAT_USB_HUB_R")
			(options
				(clearance outline)
				(anchor circle)
			)
			(primitives
				(gr_poly
					(pts
						(arc
							(start -0.1778 0.2794)
							(mid -0.249642 0.249642)
							(end -0.2794 0.1778)
						)
						(arc
							(start -0.2794 -0.1778)
							(mid -0.249642 -0.249642)
							(end -0.1778 -0.2794)
						)
						(arc
							(start 0.1778 -0.2794)
							(mid 0.249642 -0.249642)
							(end 0.2794 -0.1778)
						)
						(arc
							(start 0.2794 0.1778)
							(mid 0.249642 0.249642)
							(end 0.1778 0.2794)
						)
					)
					(width 0)
					(fill yes)
				)
			)
		)
		(pad "2" smd custom
			(at 0 0.4445)
			(size 0.1397 0.1397)
			(layers "B.Cu" "B.Mask" "B.Paste")
			(net "SMDAT_USB_HUB")
			(options
				(clearance outline)
				(anchor circle)
			)
			(primitives
				(gr_poly
					(pts
						(arc
							(start -0.1778 0.2794)
							(mid -0.249642 0.249642)
							(end -0.2794 0.1778)
						)
						(arc
							(start -0.2794 -0.1778)
							(mid -0.249642 -0.249642)
							(end -0.1778 -0.2794)
						)
						(arc
							(start 0.1778 -0.2794)
							(mid 0.249642 -0.249642)
							(end 0.2794 -0.1778)
						)
						(arc
							(start 0.2794 0.1778)
							(mid 0.249642 0.249642)
							(end 0.1778 0.2794)
						)
					)
					(width 0)
					(fill yes)
				)
			)
		)
	)
	(footprint ""
		(layer "B.Cu")
		(at 131.318 -0.4699)
		(property "Reference" "R97"
			(at 0 0 0)
			(layer "B.SilkS")
			(hide yes)
			(effects
				(font
					(size 1.27 1.27)
				)
				(justify mirror)
			)
		)
		(property "Value" "10KR2F-2-GP"
			(at -0.064008 -3.993896 0)
			(unlocked yes)
			(layer "B.Fab")
			(hide yes)
			(effects
				(font
					(size 1.016 1.016)
					(thickness 0.1524)
				)
				(justify mirror)
			)
		)
		(property "Device Type" "R402H16"
			(at -0.064008 -5.517896 0)
			(unlocked yes)
			(layer "B.Fab")
			(hide yes)
			(effects
				(font
					(size 1.016 1.016)
					(thickness 0.1524)
				)
				(justify mirror)
			)
		)
		(duplicate_pad_numbers_are_jumpers no)
		(fp_line
			(start -0.508 -0.9398)
			(end 0.508 -0.9398)
			(stroke
				(width 0.1524)
				(type default)
			)
			(layer "B.SilkS")
		)
		(fp_line
			(start 0.508 -0.9398)
			(end 0.508 0.9398)
			(stroke
				(width 0.1524)
				(type default)
			)
			(layer "B.SilkS")
		)
		(fp_rect
			(start 0.508 0.9398)
			(end -0.508 -0.9398)
			(stroke
				(width 0)
				(type default)
			)
			(fill no)
			(layer "B.CrtYd")
		)
		(fp_rect
			(start 0.508 0.9398)
			(end -0.508 -0.9398)
			(stroke
				(width 0)
				(type default)
			)
			(fill no)
			(layer "B.Fab")
		)
		(pad "1" smd custom
			(at 0 -0.4445 180)
			(size 0.1397 0.1397)
			(layers "B.Cu" "B.Mask" "B.Paste")
			(net "PU_P_I2CMUX_INT2_N")
			(options
				(clearance outline)
				(anchor circle)
			)
			(primitives
				(gr_poly
					(pts
						(arc
							(start -0.1778 0.2794)
							(mid -0.249642 0.249642)
							(end -0.2794 0.1778)
						)
						(arc
							(start -0.2794 -0.1778)
							(mid -0.249642 -0.249642)
							(end -0.1778 -0.2794)
						)
						(arc
							(start 0.1778 -0.2794)
							(mid 0.249642 -0.249642)
							(end 0.2794 -0.1778)
						)
						(arc
							(start 0.2794 0.1778)
							(mid 0.249642 0.249642)
							(end 0.1778 0.2794)
						)
					)
					(width 0)
					(fill yes)
				)
			)
		)
		(pad "2" smd custom
			(at 0 0.4445 180)
			(size 0.1397 0.1397)
			(layers "B.Cu" "B.Mask" "B.Paste")
			(net "P3V3_STBY")
			(options
				(clearance outline)
				(anchor circle)
			)
			(primitives
				(gr_poly
					(pts
						(arc
							(start -0.1778 0.2794)
							(mid -0.249642 0.249642)
							(end -0.2794 0.1778)
						)
						(arc
							(start -0.2794 -0.1778)
							(mid -0.249642 -0.249642)
							(end -0.1778 -0.2794)
						)
						(arc
							(start 0.1778 -0.2794)
							(mid 0.249642 -0.249642)
							(end 0.2794 -0.1778)
						)
						(arc
							(start 0.2794 0.1778)
							(mid 0.249642 0.249642)
							(end 0.1778 0.2794)
						)
					)
					(width 0)
					(fill yes)
				)
			)
		)
	)
	(footprint ""
		(layer "B.Cu")
		(at 26.7208 -7.0612)
		(property "Reference" "PR3"
			(at 0 0 0)
			(layer "B.SilkS")
			(hide yes)
			(effects
				(font
					(size 1.27 1.27)
				)
				(justify mirror)
			)
		)
		(property "Value" "10KR2F-2-GP"
			(at -0.064008 -3.993896 0)
			(unlocked yes)
			(layer "B.Fab")
			(hide yes)
			(effects
				(font
					(size 1.016 1.016)
					(thickness 0.1524)
				)
				(justify mirror)
			)
		)
		(property "Device Type" "R402H16"
			(at -0.064008 -5.517896 0)
			(unlocked yes)
			(layer "B.Fab")
			(hide yes)
			(effects
				(font
					(size 1.016 1.016)
					(thickness 0.1524)
				)
				(justify mirror)
			)
		)
		(duplicate_pad_numbers_are_jumpers no)
		(fp_line
			(start -0.508 -0.9398)
			(end 0.508 -0.9398)
			(stroke
				(width 0.1524)
				(type default)
			)
			(layer "B.SilkS")
		)
		(fp_line
			(start 0.508 -0.9398)
			(end 0.508 0.9398)
			(stroke
				(width 0.1524)
				(type default)
			)
			(layer "B.SilkS")
		)
		(fp_rect
			(start 0.508 0.9398)
			(end -0.508 -0.9398)
			(stroke
				(width 0)
				(type default)
			)
			(fill no)
			(layer "B.CrtYd")
		)
		(fp_rect
			(start 0.508 0.9398)
			(end -0.508 -0.9398)
			(stroke
				(width 0)
				(type default)
			)
			(fill no)
			(layer "B.Fab")
		)
		(pad "1" smd custom
			(at 0 -0.4445 180)
			(size 0.1397 0.1397)
			(layers "B.Cu" "B.Mask" "B.Paste")
			(net "P3V3_PG")
			(options
				(clearance outline)
				(anchor circle)
			)
			(primitives
				(gr_poly
					(pts
						(arc
							(start -0.1778 0.2794)
							(mid -0.249642 0.249642)
							(end -0.2794 0.1778)
						)
						(arc
							(start -0.2794 -0.1778)
							(mid -0.249642 -0.249642)
							(end -0.1778 -0.2794)
						)
						(arc
							(start 0.1778 -0.2794)
							(mid 0.249642 -0.249642)
							(end 0.2794 -0.1778)
						)
						(arc
							(start 0.2794 0.1778)
							(mid 0.249642 0.249642)
							(end 0.1778 0.2794)
						)
					)
					(width 0)
					(fill yes)
				)
			)
		)
		(pad "2" smd custom
			(at 0 0.4445 180)
			(size 0.1397 0.1397)
			(layers "B.Cu" "B.Mask" "B.Paste")
			(net "P3V3_VCC")
			(options
				(clearance outline)
				(anchor circle)
			)
			(primitives
				(gr_poly
					(pts
						(arc
							(start -0.1778 0.2794)
							(mid -0.249642 0.249642)
							(end -0.2794 0.1778)
						)
						(arc
							(start -0.2794 -0.1778)
							(mid -0.249642 -0.249642)
							(end -0.1778 -0.2794)
						)
						(arc
							(start 0.1778 -0.2794)
							(mid 0.249642 -0.249642)
							(end 0.2794 -0.1778)
						)
						(arc
							(start 0.2794 0.1778)
							(mid 0.249642 0.249642)
							(end 0.1778 0.2794)
						)
					)
					(width 0)
					(fill yes)
				)
			)
		)
	)
)
